(kicad_pcb
	(version 20260206)
	(generator "pcbnew")
	(generator_version "10.0")
	(general
		(thickness 1.6)
		(legacy_teardrops no)
	)
	(paper "A4")
	(title_block
		(title "04192023_DAF0TMB3IC0_F0TG_MB_C_brd_V02_OCP.brd")
		(comment 1 "Grand Teton / footprints 85-91 of 8354")
	)
	(layers
		(0 "F.Cu" signal "TOP")
		(4 "In1.Cu" signal "GND")
		(6 "In2.Cu" signal "IN1")
		(8 "In3.Cu" signal "GND1")
		(10 "In4.Cu" signal "IN2")
		(12 "In5.Cu" signal "GND2")
		(14 "In6.Cu" signal "IN3")
		(16 "In7.Cu" signal "GND3")
		(18 "In8.Cu" signal "VCC")
		(20 "In9.Cu" signal "VCC1")
		(22 "In10.Cu" signal "GND4")
		(24 "In11.Cu" signal "IN4")
		(26 "In12.Cu" signal "GND5")
		(28 "In13.Cu" signal "IN5")
		(30 "In14.Cu" signal "GND6")
		(32 "In15.Cu" signal "IN6")
		(34 "In16.Cu" signal "GND7")
		(2 "B.Cu" signal "BOTTOM")
		(9 "F.Adhes" user "F.Adhesive")
		(11 "B.Adhes" user "B.Adhesive")
		(13 "F.Paste" user "Package Geometry/Pastemask Top")
		(15 "B.Paste" user "Package Geometry/Pastemask Bottom")
		(5 "F.SilkS" user "Ref Des/Silkscreen Top")
		(7 "B.SilkS" user "Ref Des/Silkscreen Bottom")
		(1 "F.Mask" user "Board Geometry/Soldermask Top")
		(3 "B.Mask" user "Board Geometry/Soldermask Bottom")
		(17 "Dwgs.User" user "User.Drawings")
		(19 "Cmts.User" user "User.Comments")
		(21 "Eco1.User" user "User.Eco1")
		(23 "Eco2.User" user "User.Eco2")
		(25 "Edge.Cuts" user "Board Geometry/Outline")
		(27 "Margin" user)
		(31 "F.CrtYd" user "Package Geometry/Place Bound Top")
		(29 "B.CrtYd" user "Package Geometry/Place Bound Bottom")
		(35 "F.Fab" user "Ref Des/Assembly Top")
		(33 "B.Fab" user "Ref Des/Assembly Bottom")
	)
	(footprint ""
		(layer "F.Cu")
		(at 165.2016 -440.182)
		(property "Reference" "R2831"
			(at 0 0 0)
			(layer "F.SilkS")
			(hide yes)
			(effects
				(font
					(size 1.27 1.27)
				)
			)
		)
		(property "Value" ""
			(at 0 0 0)
			(layer "F.Fab")
			(effects
				(font
					(size 1.27 1.27)
				)
			)
		)
		(duplicate_pad_numbers_are_jumpers no)
		(fp_line
			(start -0.7874 -0.4064)
			(end 0.7874 -0.4064)
			(stroke
				(width 0.1524)
				(type default)
			)
			(layer "F.SilkS")
		)
		(fp_line
			(start -0.7874 0.4064)
			(end -0.7874 -0.4064)
			(stroke
				(width 0.1524)
				(type default)
			)
			(layer "F.SilkS")
		)
		(fp_line
			(start 0.7874 -0.4064)
			(end 0.7874 0.4064)
			(stroke
				(width 0.1524)
				(type default)
			)
			(layer "F.SilkS")
		)
		(fp_line
			(start 0.7874 0.4064)
			(end -0.7874 0.4064)
			(stroke
				(width 0.1524)
				(type default)
			)
			(layer "F.SilkS")
		)
		(fp_line
			(start -0.67945 -0.305054)
			(end -0.12065 -0.305054)
			(stroke
				(width 0.1)
				(type default)
			)
			(layer "F.Fab")
		)
		(fp_line
			(start -0.67945 0.3048)
			(end -0.67945 -0.305054)
			(stroke
				(width 0.1)
				(type default)
			)
			(layer "F.Fab")
		)
		(fp_line
			(start -0.12065 -0.305054)
			(end -0.12065 -0.2794)
			(stroke
				(width 0.1)
				(type default)
			)
			(layer "F.Fab")
		)
		(fp_line
			(start -0.12065 -0.2794)
			(end 0.12065 -0.2794)
			(stroke
				(width 0.1)
				(type default)
			)
			(layer "F.Fab")
		)
		(fp_line
			(start -0.12065 0.2794)
			(end -0.12065 0.3048)
			(stroke
				(width 0.1)
				(type default)
			)
			(layer "F.Fab")
		)
		(fp_line
			(start -0.12065 0.3048)
			(end -0.67945 0.3048)
			(stroke
				(width 0.1)
				(type default)
			)
			(layer "F.Fab")
		)
		(fp_line
			(start 0.120396 0.2794)
			(end -0.12065 0.2794)
			(stroke
				(width 0.1)
				(type default)
			)
			(layer "F.Fab")
		)
		(fp_line
			(start 0.120396 0.3048)
			(end 0.120396 0.2794)
			(stroke
				(width 0.1)
				(type default)
			)
			(layer "F.Fab")
		)
		(fp_line
			(start 0.12065 -0.3048)
			(end 0.67945 -0.3048)
			(stroke
				(width 0.1)
				(type default)
			)
			(layer "F.Fab")
		)
		(fp_line
			(start 0.12065 -0.2794)
			(end 0.12065 -0.3048)
			(stroke
				(width 0.1)
				(type default)
			)
			(layer "F.Fab")
		)
		(fp_line
			(start 0.67945 -0.3048)
			(end 0.67945 0.3048)
			(stroke
				(width 0.1)
				(type default)
			)
			(layer "F.Fab")
		)
		(fp_line
			(start 0.67945 0.3048)
			(end 0.120396 0.3048)
			(stroke
				(width 0.1)
				(type default)
			)
			(layer "F.Fab")
		)
		(pad "1" smd circle
			(at -0.40005 0)
			(size 0 0)
			(layers "F.Cu" "F.Mask" "F.Paste")
			(net "BIC_MONITER")
		)
		(pad "2" smd circle
			(at 0.40005 0)
			(size 0 0)
			(layers "F.Cu" "F.Mask" "F.Paste")
			(net "GND")
		)
	)
	(footprint ""
		(layer "F.Cu")
		(at 273.635978 -380.66853)
		(property "Reference" "PR2531"
			(at 0 0 0)
			(layer "F.SilkS")
			(hide yes)
			(effects
				(font
					(size 1.27 1.27)
				)
			)
		)
		(property "Value" ""
			(at 0 0 0)
			(layer "F.Fab")
			(effects
				(font
					(size 1.27 1.27)
				)
			)
		)
		(duplicate_pad_numbers_are_jumpers no)
		(fp_line
			(start -0.7874 -0.4064)
			(end 0.7874 -0.4064)
			(stroke
				(width 0.1524)
				(type default)
			)
			(layer "F.SilkS")
		)
		(fp_line
			(start -0.7874 0.4064)
			(end -0.7874 -0.4064)
			(stroke
				(width 0.1524)
				(type default)
			)
			(layer "F.SilkS")
		)
		(fp_line
			(start 0.7874 -0.4064)
			(end 0.7874 0.4064)
			(stroke
				(width 0.1524)
				(type default)
			)
			(layer "F.SilkS")
		)
		(fp_line
			(start 0.7874 0.4064)
			(end -0.7874 0.4064)
			(stroke
				(width 0.1524)
				(type default)
			)
			(layer "F.SilkS")
		)
		(fp_line
			(start -0.67945 -0.305054)
			(end -0.12065 -0.305054)
			(stroke
				(width 0.1)
				(type default)
			)
			(layer "F.Fab")
		)
		(fp_line
			(start -0.67945 0.3048)
			(end -0.67945 -0.305054)
			(stroke
				(width 0.1)
				(type default)
			)
			(layer "F.Fab")
		)
		(fp_line
			(start -0.12065 -0.305054)
			(end -0.12065 -0.2794)
			(stroke
				(width 0.1)
				(type default)
			)
			(layer "F.Fab")
		)
		(fp_line
			(start -0.12065 -0.2794)
			(end 0.12065 -0.2794)
			(stroke
				(width 0.1)
				(type default)
			)
			(layer "F.Fab")
		)
		(fp_line
			(start -0.12065 0.2794)
			(end -0.12065 0.3048)
			(stroke
				(width 0.1)
				(type default)
			)
			(layer "F.Fab")
		)
		(fp_line
			(start -0.12065 0.3048)
			(end -0.67945 0.3048)
			(stroke
				(width 0.1)
				(type default)
			)
			(layer "F.Fab")
		)
		(fp_line
			(start 0.120396 0.2794)
			(end -0.12065 0.2794)
			(stroke
				(width 0.1)
				(type default)
			)
			(layer "F.Fab")
		)
		(fp_line
			(start 0.120396 0.3048)
			(end 0.120396 0.2794)
			(stroke
				(width 0.1)
				(type default)
			)
			(layer "F.Fab")
		)
		(fp_line
			(start 0.12065 -0.3048)
			(end 0.67945 -0.3048)
			(stroke
				(width 0.1)
				(type default)
			)
			(layer "F.Fab")
		)
		(fp_line
			(start 0.12065 -0.2794)
			(end 0.12065 -0.3048)
			(stroke
				(width 0.1)
				(type default)
			)
			(layer "F.Fab")
		)
		(fp_line
			(start 0.67945 -0.3048)
			(end 0.67945 0.3048)
			(stroke
				(width 0.1)
				(type default)
			)
			(layer "F.Fab")
		)
		(fp_line
			(start 0.67945 0.3048)
			(end 0.120396 0.3048)
			(stroke
				(width 0.1)
				(type default)
			)
			(layer "F.Fab")
		)
		(pad "1" smd circle
			(at -0.40005 0)
			(size 0 0)
			(layers "F.Cu" "F.Mask" "F.Paste")
			(net "P12V_HSC_GATE_G4")
		)
		(pad "2" smd circle
			(at 0.40005 0)
			(size 0 0)
			(layers "F.Cu" "F.Mask" "F.Paste")
			(net "P12V_HSC_GATE2")
		)
	)
	(footprint ""
		(layer "F.Cu")
		(at 95.428816 -182.616602 90)
		(property "Reference" "PC292_3"
			(at 0 0 90)
			(layer "F.SilkS")
			(hide yes)
			(effects
				(font
					(size 1.27 1.27)
				)
			)
		)
		(property "Value" ""
			(at 0 0 90)
			(layer "F.Fab")
			(effects
				(font
					(size 1.27 1.27)
				)
			)
		)
		(duplicate_pad_numbers_are_jumpers no)
		(fp_line
			(start 0.7874 -0.4064)
			(end 0.7874 0.4064)
			(stroke
				(width 0.1524)
				(type default)
			)
			(layer "F.SilkS")
		)
		(fp_line
			(start -0.7874 -0.4064)
			(end 0.7874 -0.4064)
			(stroke
				(width 0.1524)
				(type default)
			)
			(layer "F.SilkS")
		)
		(fp_line
			(start 0.7874 0.4064)
			(end -0.7874 0.4064)
			(stroke
				(width 0.1524)
				(type default)
			)
			(layer "F.SilkS")
		)
		(fp_line
			(start -0.7874 0.4064)
			(end -0.7874 -0.4064)
			(stroke
				(width 0.1524)
				(type default)
			)
			(layer "F.SilkS")
		)
		(fp_line
			(start -0.12065 -0.305054)
			(end -0.12065 -0.2794)
			(stroke
				(width 0.1)
				(type default)
			)
			(layer "F.Fab")
		)
		(fp_line
			(start -0.67945 -0.305054)
			(end -0.12065 -0.305054)
			(stroke
				(width 0.1)
				(type default)
			)
			(layer "F.Fab")
		)
		(fp_line
			(start 0.67945 -0.3048)
			(end 0.67945 0.3048)
			(stroke
				(width 0.1)
				(type default)
			)
			(layer "F.Fab")
		)
		(fp_line
			(start 0.12065 -0.3048)
			(end 0.67945 -0.3048)
			(stroke
				(width 0.1)
				(type default)
			)
			(layer "F.Fab")
		)
		(fp_line
			(start 0.12065 -0.2794)
			(end 0.12065 -0.3048)
			(stroke
				(width 0.1)
				(type default)
			)
			(layer "F.Fab")
		)
		(fp_line
			(start -0.12065 -0.2794)
			(end 0.12065 -0.2794)
			(stroke
				(width 0.1)
				(type default)
			)
			(layer "F.Fab")
		)
		(fp_line
			(start 0.120396 0.2794)
			(end -0.12065 0.2794)
			(stroke
				(width 0.1)
				(type default)
			)
			(layer "F.Fab")
		)
		(fp_line
			(start -0.12065 0.2794)
			(end -0.12065 0.3048)
			(stroke
				(width 0.1)
				(type default)
			)
			(layer "F.Fab")
		)
		(fp_line
			(start 0.67945 0.3048)
			(end 0.120396 0.3048)
			(stroke
				(width 0.1)
				(type default)
			)
			(layer "F.Fab")
		)
		(fp_line
			(start 0.120396 0.3048)
			(end 0.120396 0.2794)
			(stroke
				(width 0.1)
				(type default)
			)
			(layer "F.Fab")
		)
		(fp_line
			(start -0.12065 0.3048)
			(end -0.67945 0.3048)
			(stroke
				(width 0.1)
				(type default)
			)
			(layer "F.Fab")
		)
		(fp_line
			(start -0.67945 0.3048)
			(end -0.67945 -0.305054)
			(stroke
				(width 0.1)
				(type default)
			)
			(layer "F.Fab")
		)
		(pad "1" smd circle
			(at -0.40005 0 90)
			(size 0 0)
			(layers "F.Cu" "F.Mask" "F.Paste")
			(net "SW_P12V_AUX_PVDDCR_CPU0_P1_FLT")
		)
		(pad "2" smd circle
			(at 0.40005 0 90)
			(size 0 0)
			(layers "F.Cu" "F.Mask" "F.Paste")
			(net "GND")
		)
	)
	(footprint ""
		(layer "F.Cu")
		(at 83.222084 -40.67048 180)
		(property "Reference" "R6056"
			(at 0 0 180)
			(layer "F.SilkS")
			(hide yes)
			(effects
				(font
					(size 1.27 1.27)
				)
			)
		)
		(property "Value" ""
			(at 0 0 180)
			(layer "F.Fab")
			(effects
				(font
					(size 1.27 1.27)
				)
			)
		)
		(duplicate_pad_numbers_are_jumpers no)
		(fp_line
			(start 0.7874 0.4064)
			(end -0.7874 0.4064)
			(stroke
				(width 0.1524)
				(type default)
			)
			(layer "F.SilkS")
		)
		(fp_line
			(start 0.7874 -0.4064)
			(end 0.7874 0.4064)
			(stroke
				(width 0.1524)
				(type default)
			)
			(layer "F.SilkS")
		)
		(fp_line
			(start -0.7874 0.4064)
			(end -0.7874 -0.4064)
			(stroke
				(width 0.1524)
				(type default)
			)
			(layer "F.SilkS")
		)
		(fp_line
			(start -0.7874 -0.4064)
			(end 0.7874 -0.4064)
			(stroke
				(width 0.1524)
				(type default)
			)
			(layer "F.SilkS")
		)
		(fp_line
			(start 0.67945 0.3048)
			(end 0.120396 0.3048)
			(stroke
				(width 0.1)
				(type default)
			)
			(layer "F.Fab")
		)
		(fp_line
			(start 0.67945 -0.3048)
			(end 0.67945 0.3048)
			(stroke
				(width 0.1)
				(type default)
			)
			(layer "F.Fab")
		)
		(fp_line
			(start 0.12065 -0.2794)
			(end 0.12065 -0.3048)
			(stroke
				(width 0.1)
				(type default)
			)
			(layer "F.Fab")
		)
		(fp_line
			(start 0.12065 -0.3048)
			(end 0.67945 -0.3048)
			(stroke
				(width 0.1)
				(type default)
			)
			(layer "F.Fab")
		)
		(fp_line
			(start 0.120396 0.3048)
			(end 0.120396 0.2794)
			(stroke
				(width 0.1)
				(type default)
			)
			(layer "F.Fab")
		)
		(fp_line
			(start 0.120396 0.2794)
			(end -0.12065 0.2794)
			(stroke
				(width 0.1)
				(type default)
			)
			(layer "F.Fab")
		)
		(fp_line
			(start -0.12065 0.3048)
			(end -0.67945 0.3048)
			(stroke
				(width 0.1)
				(type default)
			)
			(layer "F.Fab")
		)
		(fp_line
			(start -0.12065 0.2794)
			(end -0.12065 0.3048)
			(stroke
				(width 0.1)
				(type default)
			)
			(layer "F.Fab")
		)
		(fp_line
			(start -0.12065 -0.2794)
			(end 0.12065 -0.2794)
			(stroke
				(width 0.1)
				(type default)
			)
			(layer "F.Fab")
		)
		(fp_line
			(start -0.12065 -0.305054)
			(end -0.12065 -0.2794)
			(stroke
				(width 0.1)
				(type default)
			)
			(layer "F.Fab")
		)
		(fp_line
			(start -0.67945 0.3048)
			(end -0.67945 -0.305054)
			(stroke
				(width 0.1)
				(type default)
			)
			(layer "F.Fab")
		)
		(fp_line
			(start -0.67945 -0.305054)
			(end -0.12065 -0.305054)
			(stroke
				(width 0.1)
				(type default)
			)
			(layer "F.Fab")
		)
		(pad "1" smd circle
			(at -0.40005 0 180)
			(size 0 0)
			(layers "F.Cu" "F.Mask" "F.Paste")
			(net "RST_PERST_OCP_V3_2_BUF2_N")
		)
		(pad "2" smd circle
			(at 0.40005 0 180)
			(size 0 0)
			(layers "F.Cu" "F.Mask" "F.Paste")
			(net "RST_PERST0_OCP_V3_2_N")
		)
	)
	(footprint ""
		(layer "F.Cu")
		(at 75.7936 -385.58216)
		(property "Reference" "R782"
			(at 0 0 0)
			(layer "F.SilkS")
			(hide yes)
			(effects
				(font
					(size 1.27 1.27)
				)
			)
		)
		(property "Value" ""
			(at 0 0 0)
			(layer "F.Fab")
			(effects
				(font
					(size 1.27 1.27)
				)
			)
		)
		(duplicate_pad_numbers_are_jumpers no)
		(fp_line
			(start -0.32512 -0.175006)
			(end 0.32512 -0.175006)
			(stroke
				(width 0.1)
				(type default)
			)
			(layer "F.Fab")
		)
		(fp_line
			(start -0.32512 0.175006)
			(end -0.32512 -0.175006)
			(stroke
				(width 0.1)
				(type default)
			)
			(layer "F.Fab")
		)
		(fp_line
			(start 0.32512 -0.175006)
			(end 0.32512 0.175006)
			(stroke
				(width 0.1)
				(type default)
			)
			(layer "F.Fab")
		)
		(fp_line
			(start 0.32512 0.175006)
			(end -0.32512 0.175006)
			(stroke
				(width 0.1)
				(type default)
			)
			(layer "F.Fab")
		)
		(pad "1" smd rect
			(at -0.2667 0)
			(size 0.3048 0.381)
			(layers "F.Cu" "F.Mask" "F.Paste")
			(net "GPIO2_RT_CPU1_P1")
		)
		(pad "2" smd rect
			(at 0.2667 0 180)
			(size 0.3048 0.381)
			(layers "F.Cu" "F.Mask" "F.Paste")
			(net "GND")
		)
	)
	(footprint ""
		(layer "F.Cu")
		(at 444.700152 -47.522384 -90)
		(property "Reference" "PC2262"
			(at 0 0 270)
			(layer "F.SilkS")
			(hide yes)
			(effects
				(font
					(size 1.27 1.27)
				)
			)
		)
		(property "Value" ""
			(at 0 0 270)
			(layer "F.Fab")
			(effects
				(font
					(size 1.27 1.27)
				)
			)
		)
		(duplicate_pad_numbers_are_jumpers no)
		(fp_line
			(start -1.524 0.762)
			(end -1.524 -0.762)
			(stroke
				(width 0.1524)
				(type default)
			)
			(layer "F.SilkS")
		)
		(fp_line
			(start 1.524 0.762)
			(end -1.524 0.762)
			(stroke
				(width 0.1524)
				(type default)
			)
			(layer "F.SilkS")
		)
		(fp_line
			(start -1.524 -0.762)
			(end 1.524 -0.762)
			(stroke
				(width 0.1524)
				(type default)
			)
			(layer "F.SilkS")
		)
		(fp_line
			(start 1.524 -0.762)
			(end 1.524 0.762)
			(stroke
				(width 0.1524)
				(type default)
			)
			(layer "F.SilkS")
		)
		(fp_line
			(start -1.1049 0.724916)
			(end 1.1049 0.724916)
			(stroke
				(width 0.1)
				(type default)
			)
			(layer "F.Fab")
		)
		(fp_line
			(start 1.1049 0.724916)
			(end 1.1049 -0.724916)
			(stroke
				(width 0.1)
				(type default)
			)
			(layer "F.Fab")
		)
		(fp_line
			(start -1.1049 -0.724916)
			(end -1.1049 0.724916)
			(stroke
				(width 0.1)
				(type default)
			)
			(layer "F.Fab")
		)
		(fp_line
			(start 1.1049 -0.724916)
			(end -1.1049 -0.724916)
			(stroke
				(width 0.1)
				(type default)
			)
			(layer "F.Fab")
		)
		(pad "1" smd rect
			(at -0.889 0 90)
			(size 1.016 1.27)
			(layers "F.Cu" "F.Mask" "F.Paste")
			(net "SW_P3V3_AUX_FLT")
		)
		(pad "2" smd rect
			(at 0.889 0 90)
			(size 1.016 1.27)
			(layers "F.Cu" "F.Mask" "F.Paste")
			(net "GND")
		)
	)
	(footprint ""
		(layer "F.Cu")
		(at 296.681906 -346.714572 -90)
		(property "Reference" "PC147_IOP0_1"
			(at 0 0 270)
			(layer "F.SilkS")
			(hide yes)
			(effects
				(font
					(size 1.27 1.27)
				)
			)
		)
		(property "Value" ""
			(at 0 0 270)
			(layer "F.Fab")
			(effects
				(font
					(size 1.27 1.27)
				)
			)
		)
		(duplicate_pad_numbers_are_jumpers no)
		(fp_line
			(start -0.7874 0.4064)
			(end -0.7874 -0.4064)
			(stroke
				(width 0.1524)
				(type default)
			)
			(layer "F.SilkS")
		)
		(fp_line
			(start 0.7874 0.4064)
			(end -0.7874 0.4064)
			(stroke
				(width 0.1524)
				(type default)
			)
			(layer "F.SilkS")
		)
		(fp_line
			(start -0.7874 -0.4064)
			(end 0.7874 -0.4064)
			(stroke
				(width 0.1524)
				(type default)
			)
			(layer "F.SilkS")
		)
		(fp_line
			(start 0.7874 -0.4064)
			(end 0.7874 0.4064)
			(stroke
				(width 0.1524)
				(type default)
			)
			(layer "F.SilkS")
		)
		(fp_line
			(start -0.67945 0.3048)
			(end -0.67945 -0.305054)
			(stroke
				(width 0.1)
				(type default)
			)
			(layer "F.Fab")
		)
		(fp_line
			(start -0.12065 0.3048)
			(end -0.67945 0.3048)
			(stroke
				(width 0.1)
				(type default)
			)
			(layer "F.Fab")
		)
		(fp_line
			(start 0.120396 0.3048)
			(end 0.120396 0.2794)
			(stroke
				(width 0.1)
				(type default)
			)
			(layer "F.Fab")
		)
		(fp_line
			(start 0.67945 0.3048)
			(end 0.120396 0.3048)
			(stroke
				(width 0.1)
				(type default)
			)
			(layer "F.Fab")
		)
		(fp_line
			(start -0.12065 0.2794)
			(end -0.12065 0.3048)
			(stroke
				(width 0.1)
				(type default)
			)
			(layer "F.Fab")
		)
		(fp_line
			(start 0.120396 0.2794)
			(end -0.12065 0.2794)
			(stroke
				(width 0.1)
				(type default)
			)
			(layer "F.Fab")
		)
		(fp_line
			(start -0.12065 -0.2794)
			(end 0.12065 -0.2794)
			(stroke
				(width 0.1)
				(type default)
			)
			(layer "F.Fab")
		)
		(fp_line
			(start 0.12065 -0.2794)
			(end 0.12065 -0.3048)
			(stroke
				(width 0.1)
				(type default)
			)
			(layer "F.Fab")
		)
		(fp_line
			(start 0.12065 -0.3048)
			(end 0.67945 -0.3048)
			(stroke
				(width 0.1)
				(type default)
			)
			(layer "F.Fab")
		)
		(fp_line
			(start 0.67945 -0.3048)
			(end 0.67945 0.3048)
			(stroke
				(width 0.1)
				(type default)
			)
			(layer "F.Fab")
		)
		(fp_line
			(start -0.67945 -0.305054)
			(end -0.12065 -0.305054)
			(stroke
				(width 0.1)
				(type default)
			)
			(layer "F.Fab")
		)
		(fp_line
			(start -0.12065 -0.305054)
			(end -0.12065 -0.2794)
			(stroke
				(width 0.1)
				(type default)
			)
			(layer "F.Fab")
		)
		(pad "1" smd circle
			(at -0.40005 0 270)
			(size 0 0)
			(layers "F.Cu" "F.Mask" "F.Paste")
			(net "PVDDCR_CPU1_P0_PVCC")
		)
		(pad "2" smd circle
			(at 0.40005 0 270)
			(size 0 0)
			(layers "F.Cu" "F.Mask" "F.Paste")
			(net "GND")
		)
	)
)
